# T6G (Grand Teton) — schematic netlist excerpt (pin names and nets, part order shuffled) for the footprints in the layout excerpt that follows; sources: Cadence DE-HDL packaged netlist, KiCad conversion of 04192023_DAF0TMB3IC0_F0TG_MB_C_brd_V02_OCP.brd

R67  Q_RES  2.2K 5% CHIP  pkg 0402LF  page 250 : A = P3V3_AUX ; B = SMB_FRU_3V3AUX_SDA
R287  Q_RES  4.7K 5% EMPTY  pkg 0402LF  page 28 : A = GND ; B = CPU0_PWR_GOOD

(kicad_pcb
	(version 20260206)
	(generator "pcbnew")
	(generator_version "10.0")
	(general
		(thickness 1.6)
		(legacy_teardrops no)
	)
	(paper "A4")
	(title_block
		(title "04192023_DAF0TMB3IC0_F0TG_MB_C_brd_V02_OCP.brd")
		(comment 1 "Grand Teton / footprints 3862-3863 of 8354")
	)
	(layers
		(0 "F.Cu" signal "TOP")
		(4 "In1.Cu" signal "GND")
		(6 "In2.Cu" signal "IN1")
		(8 "In3.Cu" signal "GND1")
		(10 "In4.Cu" signal "IN2")
		(12 "In5.Cu" signal "GND2")
		(14 "In6.Cu" signal "IN3")
		(16 "In7.Cu" signal "GND3")
		(18 "In8.Cu" signal "VCC")
		(20 "In9.Cu" signal "VCC1")
		(22 "In10.Cu" signal "GND4")
		(24 "In11.Cu" signal "IN4")
		(26 "In12.Cu" signal "GND5")
		(28 "In13.Cu" signal "IN5")
		(30 "In14.Cu" signal "GND6")
		(32 "In15.Cu" signal "IN6")
		(34 "In16.Cu" signal "GND7")
		(2 "B.Cu" signal "BOTTOM")
		(9 "F.Adhes" user "F.Adhesive")
		(11 "B.Adhes" user "B.Adhesive")
		(13 "F.Paste" user "Package Geometry/Pastemask Top")
		(15 "B.Paste" user "Package Geometry/Pastemask Bottom")
		(5 "F.SilkS" user "Ref Des/Silkscreen Top")
		(7 "B.SilkS" user "Ref Des/Silkscreen Bottom")
		(1 "F.Mask" user "Board Geometry/Soldermask Top")
		(3 "B.Mask" user "Board Geometry/Soldermask Bottom")
		(17 "Dwgs.User" user "User.Drawings")
		(19 "Cmts.User" user "User.Comments")
		(21 "Eco1.User" user "User.Eco1")
		(23 "Eco2.User" user "User.Eco2")
		(25 "Edge.Cuts" user "Board Geometry/Outline")
		(27 "Margin" user)
		(31 "F.CrtYd" user "Package Geometry/Place Bound Top")
		(29 "B.CrtYd" user "Package Geometry/Place Bound Bottom")
		(35 "F.Fab" user "Ref Des/Assembly Top")
		(33 "B.Fab" user "Ref Des/Assembly Bottom")
	)
	(footprint ""
		(layer "F.Cu")
		(at 297.486324 -115.148614 180)
		(property "Reference" "R67"
			(at 0 0 180)
			(layer "F.SilkS")
			(hide yes)
			(effects
				(font
					(size 1.27 1.27)
				)
			)
		)
		(property "Value" ""
			(at 0 0 180)
			(layer "F.Fab")
			(effects
				(font
					(size 1.27 1.27)
				)
			)
		)
		(duplicate_pad_numbers_are_jumpers no)
		(fp_line
			(start 0.7874 0.4064)
			(end -0.7874 0.4064)
			(stroke
				(width 0.1524)
				(type default)
			)
			(layer "F.SilkS")
		)
		(fp_line
			(start 0.7874 -0.4064)
			(end 0.7874 0.4064)
			(stroke
				(width 0.1524)
				(type default)
			)
			(layer "F.SilkS")
		)
		(fp_line
			(start -0.7874 0.4064)
			(end -0.7874 -0.4064)
			(stroke
				(width 0.1524)
				(type default)
			)
			(layer "F.SilkS")
		)
		(fp_line
			(start -0.7874 -0.4064)
			(end 0.7874 -0.4064)
			(stroke
				(width 0.1524)
				(type default)
			)
			(layer "F.SilkS")
		)
		(fp_line
			(start 0.67945 0.3048)
			(end 0.120396 0.3048)
			(stroke
				(width 0.1)
				(type default)
			)
			(layer "F.Fab")
		)
		(fp_line
			(start 0.67945 -0.3048)
			(end 0.67945 0.3048)
			(stroke
				(width 0.1)
				(type default)
			)
			(layer "F.Fab")
		)
		(fp_line
			(start 0.12065 -0.2794)
			(end 0.12065 -0.3048)
			(stroke
				(width 0.1)
				(type default)
			)
			(layer "F.Fab")
		)
		(fp_line
			(start 0.12065 -0.3048)
			(end 0.67945 -0.3048)
			(stroke
				(width 0.1)
				(type default)
			)
			(layer "F.Fab")
		)
		(fp_line
			(start 0.120396 0.3048)
			(end 0.120396 0.2794)
			(stroke
				(width 0.1)
				(type default)
			)
			(layer "F.Fab")
		)
		(fp_line
			(start 0.120396 0.2794)
			(end -0.12065 0.2794)
			(stroke
				(width 0.1)
				(type default)
			)
			(layer "F.Fab")
		)
		(fp_line
			(start -0.12065 0.3048)
			(end -0.67945 0.3048)
			(stroke
				(width 0.1)
				(type default)
			)
			(layer "F.Fab")
		)
		(fp_line
			(start -0.12065 0.2794)
			(end -0.12065 0.3048)
			(stroke
				(width 0.1)
				(type default)
			)
			(layer "F.Fab")
		)
		(fp_line
			(start -0.12065 -0.2794)
			(end 0.12065 -0.2794)
			(stroke
				(width 0.1)
				(type default)
			)
			(layer "F.Fab")
		)
		(fp_line
			(start -0.12065 -0.305054)
			(end -0.12065 -0.2794)
			(stroke
				(width 0.1)
				(type default)
			)
			(layer "F.Fab")
		)
		(fp_line
			(start -0.67945 0.3048)
			(end -0.67945 -0.305054)
			(stroke
				(width 0.1)
				(type default)
			)
			(layer "F.Fab")
		)
		(fp_line
			(start -0.67945 -0.305054)
			(end -0.12065 -0.305054)
			(stroke
				(width 0.1)
				(type default)
			)
			(layer "F.Fab")
		)
		(pad "1" smd circle
			(at -0.40005 0 180)
			(size 0 0)
			(layers "F.Cu" "F.Mask" "F.Paste")
			(net "P3V3_AUX")
		)
		(pad "2" smd circle
			(at 0.40005 0 180)
			(size 0 0)
			(layers "F.Cu" "F.Mask" "F.Paste")
			(net "SMB_FRU_3V3AUX_SDA")
		)
	)
	(footprint ""
		(layer "F.Cu")
		(at 401.110958 -321.002152 -90)
		(property "Reference" "R287"
			(at 0 0 270)
			(layer "F.SilkS")
			(hide yes)
			(effects
				(font
					(size 1.27 1.27)
				)
			)
		)
		(property "Value" ""
			(at 0 0 270)
			(layer "F.Fab")
			(effects
				(font
					(size 1.27 1.27)
				)
			)
		)
		(duplicate_pad_numbers_are_jumpers no)
		(fp_line
			(start -0.7874 0.4064)
			(end -0.7874 -0.4064)
			(stroke
				(width 0.1524)
				(type default)
			)
			(layer "F.SilkS")
		)
		(fp_line
			(start 0.7874 0.4064)
			(end -0.7874 0.4064)
			(stroke
				(width 0.1524)
				(type default)
			)
			(layer "F.SilkS")
		)
		(fp_line
			(start -0.7874 -0.4064)
			(end 0.7874 -0.4064)
			(stroke
				(width 0.1524)
				(type default)
			)
			(layer "F.SilkS")
		)
		(fp_line
			(start 0.7874 -0.4064)
			(end 0.7874 0.4064)
			(stroke
				(width 0.1524)
				(type default)
			)
			(layer "F.SilkS")
		)
		(fp_line
			(start -0.67945 0.3048)
			(end -0.67945 -0.305054)
			(stroke
				(width 0.1)
				(type default)
			)
			(layer "F.Fab")
		)
		(fp_line
			(start -0.12065 0.3048)
			(end -0.67945 0.3048)
			(stroke
				(width 0.1)
				(type default)
			)
			(layer "F.Fab")
		)
		(fp_line
			(start 0.120396 0.3048)
			(end 0.120396 0.2794)
			(stroke
				(width 0.1)
				(type default)
			)
			(layer "F.Fab")
		)
		(fp_line
			(start 0.67945 0.3048)
			(end 0.120396 0.3048)
			(stroke
				(width 0.1)
				(type default)
			)
			(layer "F.Fab")
		)
		(fp_line
			(start -0.12065 0.2794)
			(end -0.12065 0.3048)
			(stroke
				(width 0.1)
				(type default)
			)
			(layer "F.Fab")
		)
		(fp_line
			(start 0.120396 0.2794)
			(end -0.12065 0.2794)
			(stroke
				(width 0.1)
				(type default)
			)
			(layer "F.Fab")
		)
		(fp_line
			(start -0.12065 -0.2794)
			(end 0.12065 -0.2794)
			(stroke
				(width 0.1)
				(type default)
			)
			(layer "F.Fab")
		)
		(fp_line
			(start 0.12065 -0.2794)
			(end 0.12065 -0.3048)
			(stroke
				(width 0.1)
				(type default)
			)
			(layer "F.Fab")
		)
		(fp_line
			(start 0.12065 -0.3048)
			(end 0.67945 -0.3048)
			(stroke
				(width 0.1)
				(type default)
			)
			(layer "F.Fab")
		)
		(fp_line
			(start 0.67945 -0.3048)
			(end 0.67945 0.3048)
			(stroke
				(width 0.1)
				(type default)
			)
			(layer "F.Fab")
		)
		(fp_line
			(start -0.67945 -0.305054)
			(end -0.12065 -0.305054)
			(stroke
				(width 0.1)
				(type default)
			)
			(layer "F.Fab")
		)
		(fp_line
			(start -0.12065 -0.305054)
			(end -0.12065 -0.2794)
			(stroke
				(width 0.1)
				(type default)
			)
			(layer "F.Fab")
		)
		(pad "1" smd circle
			(at -0.40005 0 270)
			(size 0 0)
			(layers "F.Cu" "F.Mask" "F.Paste")
			(net "GND")
		)
		(pad "2" smd circle
			(at 0.40005 0 270)
			(size 0 0)
			(layers "F.Cu" "F.Mask" "F.Paste")
			(net "CPU0_PWR_GOOD")
		)
	)
)
